(kicad_pcb
	(version 20221018)
	(generator pcbnew)
	(general
    (thickness 1.7403)
  )
	(paper "A4")
	(title_block
    (title "Data Center RDIMM DDR4 Tester")
    (date "2024-09-30")
    (rev "1.2.4")
		(comment 9 "footprints 197-203 of 690")
	)
	(layers
    (0 "F.Cu" signal)
    (1 "In1.Cu" power)
    (2 "In2.Cu" signal)
    (3 "In3.Cu" power)
    (4 "In4.Cu" power)
    (5 "In5.Cu" signal)
    (6 "In6.Cu" power)
    (7 "In7.Cu" signal)
    (8 "In8.Cu" power)
    (9 "In9.Cu" signal)
    (10 "In10.Cu" power)
    (31 "B.Cu" signal)
    (32 "B.Adhes" user "B.Adhesive")
    (33 "F.Adhes" user "F.Adhesive")
    (34 "B.Paste" user)
    (35 "F.Paste" user)
    (36 "B.SilkS" user "B.Silkscreen")
    (37 "F.SilkS" user "F.Silkscreen")
    (38 "B.Mask" user)
    (39 "F.Mask" user)
    (40 "Dwgs.User" user "User.Drawings")
    (41 "Cmts.User" user "User.Comments")
    (42 "Eco1.User" user "User.Eco1")
    (43 "Eco2.User" user "User.Eco2")
    (44 "Edge.Cuts" user)
    (45 "Margin" user)
    (46 "B.CrtYd" user "B.Courtyard")
    (47 "F.CrtYd" user "F.Courtyard")
    (48 "B.Fab" user)
    (49 "F.Fab" user)
  )
	(footprint "data-center-rdimm-ddr4-tester-footprints:AP62301WU-7-TSOT23-6" (layer "F.Cu")
    (at 152.499328 117.127008)
    (property "Author" "Antmicro")
    (property "License" "Apache-2.0")
    (property "MPN" "AP62301WU-7")
    (property "Manufacturer" "Diodes Incorporated")
    (property "Sheetfile" "supply.kicad_sch")
    (property "Sheetname" "Supply")
    (attr smd)
    (fp_text reference "U5" (at 1.310672 -0.917008) (layer "F.SilkS")
        (effects (font (size 0.7 0.7) (thickness 0.15)) (justify left bottom))
    )
    (fp_text value "AP62301WU-7" (at -0.005 2.6) (layer "F.Fab") hide
        (effects (font (size 0.7 0.7) (thickness 0.15)) (justify left bottom))
    )
    (fp_text user "${REFERENCE}" (at -1.893 6.168) (layer "F.Fab") hide
        (effects (font (size 0.7 0.7) (thickness 0.15)) (justify left bottom))
    )
    (fp_text user "License: Apache-2.0" (at -1.893 4.967) (layer "F.Fab") hide
        (effects (font (size 0.7 0.7) (thickness 0.15)) (justify left bottom))
    )
    (fp_text user "Author: Antmicro" (at -1.893 7.368) (layer "F.Fab") hide
        (effects (font (size 0.7 0.7) (thickness 0.15)) (justify left bottom))
    )
    (fp_line (start -1.4805 0.725) (end -1.4795 -0.725)
      (stroke (width 0.15) (type solid)) (layer "F.SilkS"))
    (fp_line (start -1.4805 0.725) (end -1.3905 0.725)
      (stroke (width 0.15) (type solid)) (layer "F.SilkS"))
    (fp_line (start -1.4795 -0.725) (end -1.3905 -0.725)
      (stroke (width 0.15) (type solid)) (layer "F.SilkS"))
    (fp_line (start 1.479 0.73) (end 1.38 0.73)
      (stroke (width 0.15) (type solid)) (layer "F.SilkS"))
    (fp_line (start 1.48 -0.72) (end 1.38 -0.72)
      (stroke (width 0.15) (type solid)) (layer "F.SilkS"))
    (fp_line (start 1.48 -0.72) (end 1.479 0.73)
      (stroke (width 0.15) (type solid)) (layer "F.SilkS"))
    (fp_circle (center -1.499 1.236) (end -1.45 1.236)
      (stroke (width 0.15) (type solid)) (fill solid) (layer "F.SilkS"))
    (fp_rect (start -1.65 -1.61) (end 1.65 1.61)
      (stroke (width 0.05) (type solid)) (fill none) (layer "F.CrtYd"))
    (fp_line (start -1.527 -0.833) (end 1.523 -0.833)
      (stroke (width 0.15) (type solid)) (layer "F.Fab"))
    (fp_line (start -1.527 0.491) (end -1.527 -0.833)
      (stroke (width 0.15) (type solid)) (layer "F.Fab"))
    (fp_line (start -1.527 0.491) (end -1.102 0.916)
      (stroke (width 0.15) (type solid)) (layer "F.Fab"))
    (fp_line (start -1.102 0.916) (end 1.523 0.916)
      (stroke (width 0.15) (type solid)) (layer "F.Fab"))
    (fp_line (start 1.523 -0.833) (end 1.523 0.916)
      (stroke (width 0.15) (type solid)) (layer "F.Fab"))
    (pad "1" smd rect (at -0.952 1.18) (size 0.7 0.8) (layers "F.Cu" "F.Paste" "F.Mask")
      (net 9 "GND") (pinfunction "GND") (pintype "power_in"))
    (pad "2" smd rect (at -0.001 1.18) (size 0.7 0.8) (layers "F.Cu" "F.Paste" "F.Mask")
      (net 8 "Net-(U5-SW)") (pinfunction "SW") (pintype "power_out"))
    (pad "3" smd rect (at 0.947 1.18) (size 0.7 0.8) (layers "F.Cu" "F.Paste" "F.Mask")
      (net 307 "5V0_SYS") (pinfunction "VIN") (pintype "power_in"))
    (pad "4" smd rect (at 0.947 -1.18) (size 0.7 0.8) (layers "F.Cu" "F.Paste" "F.Mask")
      (net 625 "Net-(U5-FB)") (pinfunction "FB") (pintype "input"))
    (pad "5" smd rect (at -0.001 -1.18) (size 0.7 0.8) (layers "F.Cu" "F.Paste" "F.Mask")
      (net 624 "Net-(U5-EN)") (pinfunction "EN") (pintype "input"))
    (pad "6" smd rect (at -0.952 -1.18) (size 0.7 0.8) (layers "F.Cu" "F.Paste" "F.Mask")
      (net 7 "Net-(U5-BST)") (pinfunction "BST") (pintype "output"))
  )
	(footprint "data-center-rdimm-ddr4-tester-footprints:R_0402_1005Metric" (layer "F.Cu")
    (at 141.421328 89.610008 180)
    (descr "Resistor SMD 0402")
    (tags "resistor SMD 0402")
    (property "Author" "Antmicro")
    (property "Current" "1A")
    (property "License" "Apache-2.0")
    (property "MPN" "ERJ2GE0R00X")
    (property "Manufacturer" "Panasonic")
    (property "Sheetfile" "supply.kicad_sch")
    (property "Sheetname" "Supply")
    (property "Tolerance" "")
    (property "Val" "0R")
    (property "ki_description" "0R resistor in 0402 package with unspecified tolerance")
    (attr smd)
    (fp_text reference "R38" (at -0.738672 -1.529992 180) (layer "F.SilkS")
        (effects (font (size 0.7 0.7) (thickness 0.15)) (justify left bottom))
    )
    (fp_text value "R_0R_0402" (at 0 1.4 180) (layer "F.Fab") hide
        (effects (font (size 0.7 0.7) (thickness 0.15)) (justify left bottom))
    )
    (fp_text user "License: Apache-2.0" (at -0.95 5.169 180) (layer "F.Fab") hide
        (effects (font (size 0.7 0.7) (thickness 0.15)) (justify left bottom))
    )
    (fp_text user "${REFERENCE}" (at -0.95 3.168 180) (layer "F.Fab") hide
        (effects (font (size 0.7 0.7) (thickness 0.15)) (justify left bottom))
    )
    (fp_text user "Author: Antmicro" (at -0.95 4.169 180) (layer "F.Fab") hide
        (effects (font (size 0.7 0.7) (thickness 0.15)) (justify left bottom))
    )
    (fp_rect (start -0.93 -0.47) (end 0.93 0.47)
      (stroke (width 0.05) (type solid)) (fill none) (layer "F.CrtYd"))
    (fp_rect (start -0.5 -0.25) (end 0.5 0.25)
      (stroke (width 0.15) (type solid)) (fill none) (layer "F.Fab"))
    (pad "1" smd roundrect (at -0.485 0 180) (size 0.59 0.64) (layers "F.Cu" "F.Paste" "F.Mask") (roundrect_rratio 0.25)
      (net 151 "/Supply/VCC_INT_EN") (pintype "passive"))
    (pad "2" smd roundrect (at 0.485 0 180) (size 0.59 0.64) (layers "F.Cu" "F.Paste" "F.Mask") (roundrect_rratio 0.25)
      (net 603 "Net-(U4-EN)") (pintype "passive"))
  )
	(footprint "data-center-rdimm-ddr4-tester-footprints:AP62301WU-7-TSOT23-6" (layer "F.Cu")
    (at 131.986328 92.710008 -90)
    (property "Author" "Antmicro")
    (property "License" "Apache-2.0")
    (property "MPN" "AP62301WU-7")
    (property "Manufacturer" "Diodes Incorporated")
    (property "Sheetfile" "supply.kicad_sch")
    (property "Sheetname" "Supply")
    (attr smd)
    (fp_text reference "U12" (at -1.440008 4.586328) (layer "F.SilkS")
        (effects (font (size 0.7 0.7) (thickness 0.15)) (justify left bottom))
    )
    (fp_text value "AP62301WU-7" (at -0.005 2.6 -90) (layer "F.Fab") hide
        (effects (font (size 0.7 0.7) (thickness 0.15)) (justify left bottom))
    )
    (fp_text user "License: Apache-2.0" (at -1.893 4.967 -90) (layer "F.Fab") hide
        (effects (font (size 0.7 0.7) (thickness 0.15)) (justify left bottom))
    )
    (fp_text user "${REFERENCE}" (at -1.893 6.168 -90) (layer "F.Fab") hide
        (effects (font (size 0.7 0.7) (thickness 0.15)) (justify left bottom))
    )
    (fp_text user "Author: Antmicro" (at -1.893 7.368 -90) (layer "F.Fab") hide
        (effects (font (size 0.7 0.7) (thickness 0.15)) (justify left bottom))
    )
    (fp_line (start -1.4805 0.725) (end -1.4795 -0.725)
      (stroke (width 0.15) (type solid)) (layer "F.SilkS"))
    (fp_line (start -1.4805 0.725) (end -1.3905 0.725)
      (stroke (width 0.15) (type solid)) (layer "F.SilkS"))
    (fp_line (start -1.4795 -0.725) (end -1.3905 -0.725)
      (stroke (width 0.15) (type solid)) (layer "F.SilkS"))
    (fp_line (start 1.479 0.73) (end 1.38 0.73)
      (stroke (width 0.15) (type solid)) (layer "F.SilkS"))
    (fp_line (start 1.48 -0.72) (end 1.38 -0.72)
      (stroke (width 0.15) (type solid)) (layer "F.SilkS"))
    (fp_line (start 1.48 -0.72) (end 1.479 0.73)
      (stroke (width 0.15) (type solid)) (layer "F.SilkS"))
    (fp_circle (center -1.499 1.236) (end -1.45 1.236)
      (stroke (width 0.15) (type solid)) (fill solid) (layer "F.SilkS"))
    (fp_rect (start -1.65 -1.61) (end 1.65 1.61)
      (stroke (width 0.05) (type solid)) (fill none) (layer "F.CrtYd"))
    (fp_line (start -1.527 -0.833) (end 1.523 -0.833)
      (stroke (width 0.15) (type solid)) (layer "F.Fab"))
    (fp_line (start -1.527 0.491) (end -1.527 -0.833)
      (stroke (width 0.15) (type solid)) (layer "F.Fab"))
    (fp_line (start -1.527 0.491) (end -1.102 0.916)
      (stroke (width 0.15) (type solid)) (layer "F.Fab"))
    (fp_line (start -1.102 0.916) (end 1.523 0.916)
      (stroke (width 0.15) (type solid)) (layer "F.Fab"))
    (fp_line (start 1.523 -0.833) (end 1.523 0.916)
      (stroke (width 0.15) (type solid)) (layer "F.Fab"))
    (pad "1" smd rect (at -0.952 1.18 270) (size 0.7 0.8) (layers "F.Cu" "F.Paste" "F.Mask")
      (net 9 "GND") (pinfunction "GND") (pintype "power_in"))
    (pad "2" smd rect (at -0.001 1.18 270) (size 0.7 0.8) (layers "F.Cu" "F.Paste" "F.Mask")
      (net 52 "Net-(U12-SW)") (pinfunction "SW") (pintype "power_out"))
    (pad "3" smd rect (at 0.947 1.18 270) (size 0.7 0.8) (layers "F.Cu" "F.Paste" "F.Mask")
      (net 307 "5V0_SYS") (pinfunction "VIN") (pintype "power_in"))
    (pad "4" smd rect (at 0.947 -1.18 270) (size 0.7 0.8) (layers "F.Cu" "F.Paste" "F.Mask")
      (net 653 "Net-(U12-FB)") (pinfunction "FB") (pintype "input"))
    (pad "5" smd rect (at -0.001 -1.18 270) (size 0.7 0.8) (layers "F.Cu" "F.Paste" "F.Mask")
      (net 643 "Net-(U12-EN)") (pinfunction "EN") (pintype "input"))
    (pad "6" smd rect (at -0.952 -1.18 270) (size 0.7 0.8) (layers "F.Cu" "F.Paste" "F.Mask")
      (net 51 "Net-(U12-BST)") (pinfunction "BST") (pintype "output"))
  )
	(footprint "data-center-rdimm-ddr4-tester-footprints:AP62301WU-7-TSOT23-6" (layer "F.Cu")
    (at 121.936328 106.240008)
    (property "Author" "Antmicro")
    (property "License" "Apache-2.0")
    (property "MPN" "AP62301WU-7")
    (property "Manufacturer" "Diodes Incorporated")
    (property "Sheetfile" "supply.kicad_sch")
    (property "Sheetname" "Supply")
    (attr smd)
    (fp_text reference "U9" (at -1.996328 -1.750008) (layer "F.SilkS")
        (effects (font (size 0.7 0.7) (thickness 0.15)) (justify left bottom))
    )
    (fp_text value "AP62301WU-7" (at -0.005 2.6) (layer "F.Fab") hide
        (effects (font (size 0.7 0.7) (thickness 0.15)) (justify left bottom))
    )
    (fp_text user "Author: Antmicro" (at -1.893 7.368) (layer "F.Fab") hide
        (effects (font (size 0.7 0.7) (thickness 0.15)) (justify left bottom))
    )
    (fp_text user "License: Apache-2.0" (at -1.893 4.967) (layer "F.Fab") hide
        (effects (font (size 0.7 0.7) (thickness 0.15)) (justify left bottom))
    )
    (fp_text user "${REFERENCE}" (at -1.893 6.168) (layer "F.Fab") hide
        (effects (font (size 0.7 0.7) (thickness 0.15)) (justify left bottom))
    )
    (fp_line (start -1.4805 0.725) (end -1.4795 -0.725)
      (stroke (width 0.15) (type solid)) (layer "F.SilkS"))
    (fp_line (start -1.4805 0.725) (end -1.3905 0.725)
      (stroke (width 0.15) (type solid)) (layer "F.SilkS"))
    (fp_line (start -1.4795 -0.725) (end -1.3905 -0.725)
      (stroke (width 0.15) (type solid)) (layer "F.SilkS"))
    (fp_line (start 1.479 0.73) (end 1.38 0.73)
      (stroke (width 0.15) (type solid)) (layer "F.SilkS"))
    (fp_line (start 1.48 -0.72) (end 1.38 -0.72)
      (stroke (width 0.15) (type solid)) (layer "F.SilkS"))
    (fp_line (start 1.48 -0.72) (end 1.479 0.73)
      (stroke (width 0.15) (type solid)) (layer "F.SilkS"))
    (fp_circle (center -1.499 1.236) (end -1.45 1.236)
      (stroke (width 0.15) (type solid)) (fill solid) (layer "F.SilkS"))
    (fp_rect (start -1.65 -1.61) (end 1.65 1.61)
      (stroke (width 0.05) (type solid)) (fill none) (layer "F.CrtYd"))
    (fp_line (start -1.527 -0.833) (end 1.523 -0.833)
      (stroke (width 0.15) (type solid)) (layer "F.Fab"))
    (fp_line (start -1.527 0.491) (end -1.527 -0.833)
      (stroke (width 0.15) (type solid)) (layer "F.Fab"))
    (fp_line (start -1.527 0.491) (end -1.102 0.916)
      (stroke (width 0.15) (type solid)) (layer "F.Fab"))
    (fp_line (start -1.102 0.916) (end 1.523 0.916)
      (stroke (width 0.15) (type solid)) (layer "F.Fab"))
    (fp_line (start 1.523 -0.833) (end 1.523 0.916)
      (stroke (width 0.15) (type solid)) (layer "F.Fab"))
    (pad "1" smd rect (at -0.952 1.18) (size 0.7 0.8) (layers "F.Cu" "F.Paste" "F.Mask")
      (net 9 "GND") (pinfunction "GND") (pintype "power_in"))
    (pad "2" smd rect (at -0.001 1.18) (size 0.7 0.8) (layers "F.Cu" "F.Paste" "F.Mask")
      (net 50 "Net-(U9-SW)") (pinfunction "SW") (pintype "power_out"))
    (pad "3" smd rect (at 0.947 1.18) (size 0.7 0.8) (layers "F.Cu" "F.Paste" "F.Mask")
      (net 307 "5V0_SYS") (pinfunction "VIN") (pintype "power_in"))
    (pad "4" smd rect (at 0.947 -1.18) (size 0.7 0.8) (layers "F.Cu" "F.Paste" "F.Mask")
      (net 644 "Net-(U9-FB)") (pinfunction "FB") (pintype "input"))
    (pad "5" smd rect (at -0.001 -1.18) (size 0.7 0.8) (layers "F.Cu" "F.Paste" "F.Mask")
      (net 642 "Net-(U9-EN)") (pinfunction "EN") (pintype "input"))
    (pad "6" smd rect (at -0.952 -1.18) (size 0.7 0.8) (layers "F.Cu" "F.Paste" "F.Mask")
      (net 49 "Net-(U9-BST)") (pinfunction "BST") (pintype "output"))
  )
	(footprint "data-center-rdimm-ddr4-tester-footprints:R_0402_1005Metric" (layer "F.Cu")
    (at 125.336328 105.400008 90)
    (descr "Resistor SMD 0402")
    (tags "resistor SMD 0402")
    (property "Author" "Antmicro")
    (property "License" "Apache-2.0")
    (property "MPN" "CR0402-FX-3162GLF")
    (property "Manufacturer" "Bourns")
    (property "Sheetfile" "supply.kicad_sch")
    (property "Sheetname" "Supply")
    (property "Tolerance" "1%")
    (property "Val" "31k6")
    (property "ki_description" "31k6 resistor in 0402 package with 1% tolerance")
    (attr smd)
    (fp_text reference "R49" (at -0.549992 2.203672 90) (layer "F.SilkS")
        (effects (font (size 0.7 0.7) (thickness 0.15)) (justify left bottom))
    )
    (fp_text value "R_31k6_0402" (at 0 1.4 90) (layer "F.Fab") hide
        (effects (font (size 0.7 0.7) (thickness 0.15)) (justify left bottom))
    )
    (fp_text user "License: Apache-2.0" (at -0.95 5.169 90) (layer "F.Fab") hide
        (effects (font (size 0.7 0.7) (thickness 0.15)) (justify left bottom))
    )
    (fp_text user "${REFERENCE}" (at -0.95 3.168 90) (layer "F.Fab") hide
        (effects (font (size 0.7 0.7) (thickness 0.15)) (justify left bottom))
    )
    (fp_text user "Author: Antmicro" (at -0.95 4.169 90) (layer "F.Fab") hide
        (effects (font (size 0.7 0.7) (thickness 0.15)) (justify left bottom))
    )
    (fp_rect (start -0.93 -0.47) (end 0.93 0.47)
      (stroke (width 0.05) (type solid)) (fill none) (layer "F.CrtYd"))
    (fp_rect (start -0.5 -0.25) (end 0.5 0.25)
      (stroke (width 0.15) (type solid)) (fill none) (layer "F.Fab"))
    (pad "1" smd roundrect (at -0.485 0 90) (size 0.59 0.64) (layers "F.Cu" "F.Paste" "F.Mask") (roundrect_rratio 0.25)
      (net 304 "VCC3V3") (pintype "passive"))
    (pad "2" smd roundrect (at 0.485 0 90) (size 0.59 0.64) (layers "F.Cu" "F.Paste" "F.Mask") (roundrect_rratio 0.25)
      (net 644 "Net-(U9-FB)") (pintype "passive"))
  )
	(footprint "data-center-rdimm-ddr4-tester-footprints:C_0402_1005Metric" (layer "F.Cu")
    (at 114.98 106.74 90)
    (descr "Capacitor SMD 0402")
    (tags "capacitor SMD 0402")
    (property "Author" "Antmicro")
    (property "Dielectric" "")
    (property "License" "Apache-2.0")
    (property "MPN" "04024W226MAT2A")
    (property "Manufacturer" "AVX")
    (property "Sheetfile" "supply.kicad_sch")
    (property "Sheetname" "Supply")
    (property "Val" "22u")
    (property "Voltage" "")
    (property "ki_description" " ")
    (attr smd)
    (fp_text reference "C216" (at -3.589992 0.353672 90) (layer "F.SilkS")
        (effects (font (size 0.7 0.7) (thickness 0.15)) (justify left bottom))
    )
    (fp_text value "C_22u_0402" (at 0 1.4 90) (layer "F.Fab") hide
        (effects (font (size 0.7 0.7) (thickness 0.15)) (justify left bottom))
    )
    (fp_text user "Author: Antmicro" (at -0.932 4.17 90) (layer "F.Fab") hide
        (effects (font (size 0.7 0.7) (thickness 0.15)) (justify left bottom))
    )
    (fp_text user "${REFERENCE}" (at -0.932 3.168 90) (layer "F.Fab") hide
        (effects (font (size 0.7 0.7) (thickness 0.15)) (justify left bottom))
    )
    (fp_text user "License: Apache-2.0" (at -0.932 5.17 90) (layer "F.Fab") hide
        (effects (font (size 0.7 0.7) (thickness 0.15)) (justify left bottom))
    )
    (fp_rect (start -0.94 -0.47) (end 0.94 0.47)
      (stroke (width 0.05) (type solid)) (fill none) (layer "F.CrtYd"))
    (fp_rect (start -0.499 -0.249) (end 0.499 0.249)
      (stroke (width 0.15) (type solid)) (fill none) (layer "F.Fab"))
    (pad "1" smd roundrect (at -0.484 0 90) (size 0.59 0.64) (layers "F.Cu" "F.Paste" "F.Mask") (roundrect_rratio 0.25)
      (net 304 "VCC3V3") (pintype "passive"))
    (pad "2" smd roundrect (at 0.484 0 90) (size 0.59 0.64) (layers "F.Cu" "F.Paste" "F.Mask") (roundrect_rratio 0.25)
      (net 9 "GND") (pintype "passive"))
  )
	(footprint "data-center-rdimm-ddr4-tester-footprints:C_0603_1608Metric" (layer "F.Cu")
    (at 123.916328 102.890008 90)
    (descr "Capacitor SMD 0603")
    (tags "capacitor 0603")
    (property "Author" "Antmicro")
    (property "Dielectric" "")
    (property "License" "Apache-2.0")
    (property "MPN" "GRM188R60J476ME15D")
    (property "Manufacturer" "Murata")
    (property "Sheetfile" "supply.kicad_sch")
    (property "Sheetname" "Supply")
    (property "Val" "47u")
    (property "Voltage" "")
    (property "ki_description" " ")
    (attr smd)
    (fp_text reference "C183" (at -1.269992 4.333672 90) (layer "F.SilkS")
        (effects (font (size 0.7 0.7) (thickness 0.15)) (justify left bottom))
    )
    (fp_text value "C_47u_0603" (at 0 1.6 90) (layer "F.Fab") hide
        (effects (font (size 0.7 0.7) (thickness 0.15)) (justify left bottom))
    )
    (fp_text user "Author: Antmicro" (at -1.682 4.894 90) (layer "F.Fab") hide
        (effects (font (size 0.7 0.7) (thickness 0.15)) (justify left bottom))
    )
    (fp_text user "${REFERENCE}" (at -1.682 3.895 90) (layer "F.Fab") hide
        (effects (font (size 0.7 0.7) (thickness 0.15)) (justify left bottom))
    )
    (fp_text user "License: Apache-2.0" (at -1.682 5.895 90) (layer "F.Fab") hide
        (effects (font (size 0.7 0.7) (thickness 0.15)) (justify left bottom))
    )
    (fp_line (start -0.3 -0.3) (end 0.3 -0.3)
      (stroke (width 0.15) (type solid)) (layer "F.SilkS"))
    (fp_line (start -0.3 0.3) (end 0.3 0.3)
      (stroke (width 0.15) (type solid)) (layer "F.SilkS"))
    (fp_rect (start -1.24 -0.7) (end 1.24 0.7)
      (stroke (width 0.05) (type solid)) (fill none) (layer "F.CrtYd"))
    (fp_rect (start -0.8 -0.4) (end 0.8 0.4)
      (stroke (width 0.15) (type solid)) (fill none) (layer "F.Fab"))
    (pad "1" smd roundrect (at -0.7 0 90) (size 0.6 0.8) (layers "F.Cu" "F.Paste" "F.Mask") (roundrect_rratio 0.2)
      (net 104 "VCC5V0") (pintype "passive"))
    (pad "2" smd roundrect (at 0.7 0 90) (size 0.6 0.8) (layers "F.Cu" "F.Paste" "F.Mask") (roundrect_rratio 0.2)
      (net 9 "GND") (pintype "passive"))
  )
)
